(kicad_pcb
	(version 20260206)
	(generator "pcbnew")
	(generator_version "10.0")
	(general
		(thickness 1.6)
		(legacy_teardrops no)
	)
	(paper "A4")
	(title_block
		(title "Bryce Canyon_IOM_M2_16342-2_OCP.brd")
		(comment 1 "Bryce Canyon / footprints 1098-1106 of 1146")
	)
	(layers
		(0 "F.Cu" signal "TOP")
		(4 "In1.Cu" signal "L2GND")
		(6 "In2.Cu" signal "L3")
		(8 "In3.Cu" signal "L4VCC")
		(10 "In4.Cu" signal "L5VCC")
		(12 "In5.Cu" signal "L6")
		(14 "In6.Cu" signal "L7GND")
		(2 "B.Cu" signal "BOTTOM")
		(9 "F.Adhes" user "F.Adhesive")
		(11 "B.Adhes" user "B.Adhesive")
		(13 "F.Paste" user "Package Geometry/Pastemask Top")
		(15 "B.Paste" user "Package Geometry/Pastemask Bottom")
		(5 "F.SilkS" user "Ref Des/Silkscreen Top")
		(7 "B.SilkS" user "Ref Des/Silkscreen Bottom")
		(1 "F.Mask" user "Board Geometry/Soldermask Top")
		(3 "B.Mask" user "Board Geometry/Soldermask Bottom")
		(17 "Dwgs.User" user "User.Drawings")
		(19 "Cmts.User" user "User.Comments")
		(21 "Eco1.User" user "User.Eco1")
		(23 "Eco2.User" user "User.Eco2")
		(25 "Edge.Cuts" user "Board Geometry/Outline")
		(27 "Margin" user)
		(31 "F.CrtYd" user "Package Geometry/Place Bound Top")
		(29 "B.CrtYd" user "Package Geometry/Place Bound Bottom")
		(35 "F.Fab" user "Ref Des/Assembly Top")
		(33 "B.Fab" user "Ref Des/Assembly Bottom")
	)
	(footprint ""
		(layer "B.Cu")
		(at 175.22825 -119.541544 180)
		(property "Reference" "C633"
			(at 0 0 0)
			(layer "B.SilkS")
			(hide yes)
			(effects
				(font
					(size 1.27 1.27)
				)
				(justify mirror)
			)
		)
		(property "Value" "SCD1U16V2KX-3GP"
			(at -1.1811 -2.7051 180)
			(unlocked yes)
			(layer "B.Fab")
			(hide yes)
			(effects
				(font
					(size 1.016 1.016)
					(thickness 0.1524)
				)
				(justify mirror)
			)
		)
		(property "Device Type" "C402H22"
			(at -1.1811 -4.2291 180)
			(unlocked yes)
			(layer "B.Fab")
			(hide yes)
			(effects
				(font
					(size 1.016 1.016)
					(thickness 0.1524)
				)
				(justify mirror)
			)
		)
		(duplicate_pad_numbers_are_jumpers no)
		(fp_rect
			(start 0.4318 0.9525)
			(end -0.4318 -0.9525)
			(stroke
				(width 0)
				(type default)
			)
			(fill no)
			(layer "B.CrtYd")
		)
		(fp_rect
			(start 0.4318 0.9525)
			(end -0.4318 -0.9525)
			(stroke
				(width 0)
				(type default)
			)
			(fill no)
			(layer "B.Fab")
		)
		(pad "1" smd custom
			(at 0 -0.4445)
			(size 0.1524 0.1524)
			(layers "B.Cu" "B.Mask" "B.Paste")
			(net "P1V8_STBY")
			(options
				(clearance outline)
				(anchor circle)
			)
			(primitives
				(gr_poly
					(pts
						(arc
							(start 0.3048 0.2032)
							(mid 0.275042 0.275042)
							(end 0.2032 0.3048)
						)
						(arc
							(start -0.2032 0.3048)
							(mid -0.275042 0.275042)
							(end -0.3048 0.2032)
						)
						(arc
							(start -0.3048 -0.2032)
							(mid -0.275042 -0.275042)
							(end -0.2032 -0.3048)
						)
						(arc
							(start 0.2032 -0.3048)
							(mid 0.275042 -0.275042)
							(end 0.3048 -0.2032)
						)
					)
					(width 0)
					(fill yes)
				)
			)
		)
		(pad "2" smd custom
			(at 0 0.4445)
			(size 0.1524 0.1524)
			(layers "B.Cu" "B.Mask" "B.Paste")
			(net "GND")
			(options
				(clearance outline)
				(anchor circle)
			)
			(primitives
				(gr_poly
					(pts
						(arc
							(start 0.3048 0.2032)
							(mid 0.275042 0.275042)
							(end 0.2032 0.3048)
						)
						(arc
							(start -0.2032 0.3048)
							(mid -0.275042 0.275042)
							(end -0.3048 0.2032)
						)
						(arc
							(start -0.3048 -0.2032)
							(mid -0.275042 -0.275042)
							(end -0.2032 -0.3048)
						)
						(arc
							(start 0.2032 -0.3048)
							(mid 0.275042 -0.275042)
							(end 0.3048 -0.2032)
						)
					)
					(width 0)
					(fill yes)
				)
			)
		)
	)
	(footprint ""
		(layer "B.Cu")
		(at 43.63212 -125.991874)
		(property "Reference" "TP84"
			(at 0 0 0)
			(layer "B.SilkS")
			(hide yes)
			(effects
				(font
					(size 1.27 1.27)
				)
				(justify mirror)
			)
		)
		(property "Value" "TPAD28-2-GP"
			(at 0.0127 -1.6637 0)
			(unlocked yes)
			(layer "B.Fab")
			(hide yes)
			(effects
				(font
					(size 1.016 1.016)
					(thickness 0.1524)
				)
				(justify mirror)
			)
		)
		(property "Device Type" "TPAD28"
			(at 0.0127 -3.1877 0)
			(unlocked yes)
			(layer "B.Fab")
			(hide yes)
			(effects
				(font
					(size 1.016 1.016)
					(thickness 0.1524)
				)
				(justify mirror)
			)
		)
		(duplicate_pad_numbers_are_jumpers no)
		(fp_poly
			(pts
				(arc
					(start 0.3556 0)
					(mid -0.3556 0)
					(end 0.3556 0)
				)
			)
			(stroke
				(width 0)
				(type default)
			)
			(fill no)
			(layer "B.CrtYd")
		)
		(fp_poly
			(pts
				(arc
					(start 0.6096 0)
					(mid -0.6096 0)
					(end 0.6096 0)
				)
			)
			(stroke
				(width 0)
				(type default)
			)
			(fill no)
			(layer "B.Fab")
		)
		(pad "1" smd circle
			(at 0 0 180)
			(size 0.7112 0.7112)
			(layers "B.Cu" "B.Mask" "B.Paste")
			(net "FM_BMC_RESET_N")
		)
	)
	(footprint ""
		(layer "B.Cu")
		(at 193.13525 -133.831584 180)
		(property "Reference" "C612"
			(at 0 0 0)
			(layer "B.SilkS")
			(hide yes)
			(effects
				(font
					(size 1.27 1.27)
				)
				(justify mirror)
			)
		)
		(property "Value" "SCD1U16V2KX-3GP"
			(at -1.1811 -2.7051 180)
			(unlocked yes)
			(layer "B.Fab")
			(hide yes)
			(effects
				(font
					(size 1.016 1.016)
					(thickness 0.1524)
				)
				(justify mirror)
			)
		)
		(property "Device Type" "C402H22"
			(at -1.1811 -4.2291 180)
			(unlocked yes)
			(layer "B.Fab")
			(hide yes)
			(effects
				(font
					(size 1.016 1.016)
					(thickness 0.1524)
				)
				(justify mirror)
			)
		)
		(duplicate_pad_numbers_are_jumpers no)
		(fp_rect
			(start 0.4318 0.9525)
			(end -0.4318 -0.9525)
			(stroke
				(width 0)
				(type default)
			)
			(fill no)
			(layer "B.CrtYd")
		)
		(fp_rect
			(start 0.4318 0.9525)
			(end -0.4318 -0.9525)
			(stroke
				(width 0)
				(type default)
			)
			(fill no)
			(layer "B.Fab")
		)
		(pad "1" smd custom
			(at 0 -0.4445)
			(size 0.1524 0.1524)
			(layers "B.Cu" "B.Mask" "B.Paste")
			(net "P3V3_M2")
			(options
				(clearance outline)
				(anchor circle)
			)
			(primitives
				(gr_poly
					(pts
						(arc
							(start 0.3048 0.2032)
							(mid 0.275042 0.275042)
							(end 0.2032 0.3048)
						)
						(arc
							(start -0.2032 0.3048)
							(mid -0.275042 0.275042)
							(end -0.3048 0.2032)
						)
						(arc
							(start -0.3048 -0.2032)
							(mid -0.275042 -0.275042)
							(end -0.2032 -0.3048)
						)
						(arc
							(start 0.2032 -0.3048)
							(mid 0.275042 -0.275042)
							(end 0.3048 -0.2032)
						)
					)
					(width 0)
					(fill yes)
				)
			)
		)
		(pad "2" smd custom
			(at 0 0.4445)
			(size 0.1524 0.1524)
			(layers "B.Cu" "B.Mask" "B.Paste")
			(net "GND")
			(options
				(clearance outline)
				(anchor circle)
			)
			(primitives
				(gr_poly
					(pts
						(arc
							(start 0.3048 0.2032)
							(mid 0.275042 0.275042)
							(end 0.2032 0.3048)
						)
						(arc
							(start -0.2032 0.3048)
							(mid -0.275042 0.275042)
							(end -0.3048 0.2032)
						)
						(arc
							(start -0.3048 -0.2032)
							(mid -0.275042 -0.275042)
							(end -0.2032 -0.3048)
						)
						(arc
							(start 0.2032 -0.3048)
							(mid 0.275042 -0.275042)
							(end 0.3048 -0.2032)
						)
					)
					(width 0)
					(fill yes)
				)
			)
		)
	)
	(footprint ""
		(layer "B.Cu")
		(at 42.418 -131.7752 180)
		(property "Reference" "R284"
			(at 0 0 0)
			(layer "B.SilkS")
			(hide yes)
			(effects
				(font
					(size 1.27 1.27)
				)
				(justify mirror)
			)
		)
		(property "Value" "33R2F-3-GP"
			(at -0.064008 -3.993896 180)
			(unlocked yes)
			(layer "B.Fab")
			(hide yes)
			(effects
				(font
					(size 1.016 1.016)
					(thickness 0.1524)
				)
				(justify mirror)
			)
		)
		(property "Device Type" "R402H16"
			(at -0.064008 -5.517896 180)
			(unlocked yes)
			(layer "B.Fab")
			(hide yes)
			(effects
				(font
					(size 1.016 1.016)
					(thickness 0.1524)
				)
				(justify mirror)
			)
		)
		(duplicate_pad_numbers_are_jumpers no)
		(fp_line
			(start 0.508 -0.9398)
			(end 0.508 0.9398)
			(stroke
				(width 0.1524)
				(type default)
			)
			(layer "B.SilkS")
		)
		(fp_line
			(start -0.508 -0.9398)
			(end 0.508 -0.9398)
			(stroke
				(width 0.1524)
				(type default)
			)
			(layer "B.SilkS")
		)
		(fp_rect
			(start 0.508 0.9398)
			(end -0.508 -0.9398)
			(stroke
				(width 0)
				(type default)
			)
			(fill no)
			(layer "B.CrtYd")
		)
		(fp_rect
			(start 0.508 0.9398)
			(end -0.508 -0.9398)
			(stroke
				(width 0)
				(type default)
			)
			(fill no)
			(layer "B.Fab")
		)
		(pad "1" smd custom
			(at 0 -0.4445)
			(size 0.1397 0.1397)
			(layers "B.Cu" "B.Mask" "B.Paste")
			(net "BMC_SPI_MOSI_R")
			(options
				(clearance outline)
				(anchor circle)
			)
			(primitives
				(gr_poly
					(pts
						(arc
							(start -0.1778 0.2794)
							(mid -0.249642 0.249642)
							(end -0.2794 0.1778)
						)
						(arc
							(start -0.2794 -0.1778)
							(mid -0.249642 -0.249642)
							(end -0.1778 -0.2794)
						)
						(arc
							(start 0.1778 -0.2794)
							(mid 0.249642 -0.249642)
							(end 0.2794 -0.1778)
						)
						(arc
							(start 0.2794 0.1778)
							(mid 0.249642 0.249642)
							(end 0.1778 0.2794)
						)
					)
					(width 0)
					(fill yes)
				)
			)
		)
		(pad "2" smd custom
			(at 0 0.4445)
			(size 0.1397 0.1397)
			(layers "B.Cu" "B.Mask" "B.Paste")
			(net "BMC_SPI_MOSI")
			(options
				(clearance outline)
				(anchor circle)
			)
			(primitives
				(gr_poly
					(pts
						(arc
							(start -0.1778 0.2794)
							(mid -0.249642 0.249642)
							(end -0.2794 0.1778)
						)
						(arc
							(start -0.2794 -0.1778)
							(mid -0.249642 -0.249642)
							(end -0.1778 -0.2794)
						)
						(arc
							(start 0.1778 -0.2794)
							(mid 0.249642 -0.249642)
							(end 0.2794 -0.1778)
						)
						(arc
							(start 0.2794 0.1778)
							(mid 0.249642 0.249642)
							(end 0.1778 0.2794)
						)
					)
					(width 0)
					(fill yes)
				)
			)
		)
	)
	(footprint ""
		(layer "B.Cu")
		(at 52.1462 -163.1442 90)
		(property "Reference" "R819"
			(at 0 0 90)
			(layer "B.SilkS")
			(hide yes)
			(effects
				(font
					(size 1.27 1.27)
				)
				(justify mirror)
			)
		)
		(property "Value" "1K4R2F-1-GP"
			(at -0.064008 -3.993896 90)
			(unlocked yes)
			(layer "B.Fab")
			(hide yes)
			(effects
				(font
					(size 1.016 1.016)
					(thickness 0.1524)
				)
				(justify mirror)
			)
		)
		(property "Device Type" "R402H16"
			(at -0.064008 -5.517896 90)
			(unlocked yes)
			(layer "B.Fab")
			(hide yes)
			(effects
				(font
					(size 1.016 1.016)
					(thickness 0.1524)
				)
				(justify mirror)
			)
		)
		(duplicate_pad_numbers_are_jumpers no)
		(fp_line
			(start 0.508 -0.9398)
			(end 0.508 0.9398)
			(stroke
				(width 0.1524)
				(type default)
			)
			(layer "B.SilkS")
		)
		(fp_line
			(start -0.508 -0.9398)
			(end 0.508 -0.9398)
			(stroke
				(width 0.1524)
				(type default)
			)
			(layer "B.SilkS")
		)
		(fp_rect
			(start 0.508 0.9398)
			(end -0.508 -0.9398)
			(stroke
				(width 0)
				(type default)
			)
			(fill no)
			(layer "B.CrtYd")
		)
		(fp_rect
			(start 0.508 0.9398)
			(end -0.508 -0.9398)
			(stroke
				(width 0)
				(type default)
			)
			(fill no)
			(layer "B.Fab")
		)
		(pad "1" smd custom
			(at 0 -0.4445 270)
			(size 0.1397 0.1397)
			(layers "B.Cu" "B.Mask" "B.Paste")
			(net "P3V3_M2")
			(options
				(clearance outline)
				(anchor circle)
			)
			(primitives
				(gr_poly
					(pts
						(arc
							(start -0.1778 0.2794)
							(mid -0.249642 0.249642)
							(end -0.2794 0.1778)
						)
						(arc
							(start -0.2794 -0.1778)
							(mid -0.249642 -0.249642)
							(end -0.1778 -0.2794)
						)
						(arc
							(start 0.1778 -0.2794)
							(mid 0.249642 -0.249642)
							(end 0.2794 -0.1778)
						)
						(arc
							(start 0.2794 0.1778)
							(mid 0.249642 0.249642)
							(end 0.1778 0.2794)
						)
					)
					(width 0)
					(fill yes)
				)
			)
		)
		(pad "2" smd custom
			(at 0 0.4445 270)
			(size 0.1397 0.1397)
			(layers "B.Cu" "B.Mask" "B.Paste")
			(net "ADC_P3V3_M2")
			(options
				(clearance outline)
				(anchor circle)
			)
			(primitives
				(gr_poly
					(pts
						(arc
							(start -0.1778 0.2794)
							(mid -0.249642 0.249642)
							(end -0.2794 0.1778)
						)
						(arc
							(start -0.2794 -0.1778)
							(mid -0.249642 -0.249642)
							(end -0.1778 -0.2794)
						)
						(arc
							(start 0.1778 -0.2794)
							(mid 0.249642 -0.249642)
							(end 0.2794 -0.1778)
						)
						(arc
							(start 0.2794 0.1778)
							(mid 0.249642 0.249642)
							(end 0.1778 0.2794)
						)
					)
					(width 0)
					(fill yes)
				)
			)
		)
	)
	(footprint ""
		(layer "B.Cu")
		(at 50.292 -132.08)
		(property "Reference" "C110"
			(at 0 0 0)
			(layer "B.SilkS")
			(hide yes)
			(effects
				(font
					(size 1.27 1.27)
				)
				(justify mirror)
			)
		)
		(property "Value" "SC1U16V3KX-5GP"
			(at 0 -2.8194 0)
			(unlocked yes)
			(layer "B.Fab")
			(hide yes)
			(effects
				(font
					(size 1.016 1.016)
					(thickness 0.1524)
				)
				(justify mirror)
			)
		)
		(property "Device Type" "C603H36"
			(at 0 -4.3434 0)
			(unlocked yes)
			(layer "B.Fab")
			(hide yes)
			(effects
				(font
					(size 1.016 1.016)
					(thickness 0.1524)
				)
				(justify mirror)
			)
		)
		(duplicate_pad_numbers_are_jumpers no)
		(fp_line
			(start -0.508 0)
			(end 0.508 0)
			(stroke
				(width 0.2032)
				(type default)
			)
			(layer "B.SilkS")
		)
		(fp_rect
			(start 0.5842 1.3335)
			(end -0.5842 -1.3335)
			(stroke
				(width 0)
				(type default)
			)
			(fill no)
			(layer "B.CrtYd")
		)
		(fp_rect
			(start 0.5842 1.3335)
			(end -0.5842 -1.3335)
			(stroke
				(width 0)
				(type default)
			)
			(fill no)
			(layer "B.Fab")
		)
		(pad "1" smd custom
			(at 0 -0.762 180)
			(size 0.2159 0.2159)
			(layers "B.Cu" "B.Mask" "B.Paste")
			(net "P1V15_STBY")
			(options
				(clearance outline)
				(anchor circle)
			)
			(primitives
				(gr_poly
					(pts
						(arc
							(start -0.3302 0.4318)
							(mid -0.402042 0.402042)
							(end -0.4318 0.3302)
						)
						(arc
							(start -0.4318 -0.3302)
							(mid -0.402042 -0.402042)
							(end -0.3302 -0.4318)
						)
						(arc
							(start 0.3302 -0.4318)
							(mid 0.402042 -0.402042)
							(end 0.4318 -0.3302)
						)
						(arc
							(start 0.4318 0.3302)
							(mid 0.402042 0.402042)
							(end 0.3302 0.4318)
						)
					)
					(width 0)
					(fill yes)
				)
			)
		)
		(pad "2" smd custom
			(at 0 0.762 180)
			(size 0.2159 0.2159)
			(layers "B.Cu" "B.Mask" "B.Paste")
			(net "GND")
			(options
				(clearance outline)
				(anchor circle)
			)
			(primitives
				(gr_poly
					(pts
						(arc
							(start -0.3302 0.4318)
							(mid -0.402042 0.402042)
							(end -0.4318 0.3302)
						)
						(arc
							(start -0.4318 -0.3302)
							(mid -0.402042 -0.402042)
							(end -0.3302 -0.4318)
						)
						(arc
							(start 0.3302 -0.4318)
							(mid 0.402042 -0.402042)
							(end 0.4318 -0.3302)
						)
						(arc
							(start 0.4318 0.3302)
							(mid 0.402042 0.402042)
							(end 0.3302 0.4318)
						)
					)
					(width 0)
					(fill yes)
				)
			)
		)
	)
	(footprint ""
		(layer "B.Cu")
		(at 92.71 -132.1054 -90)
		(property "Reference" "U100"
			(at 0 0 90)
			(layer "B.SilkS")
			(hide yes)
			(effects
				(font
					(size 1.27 1.27)
				)
				(justify mirror)
			)
		)
		(property "Value" "SNLVC1G126DCKR-GP"
			(at 2.3368 -8.6868 270)
			(unlocked yes)
			(layer "B.Fab")
			(hide yes)
			(effects
				(font
					(size 1.016 1.016)
					(thickness 0.1524)
				)
				(justify mirror)
			)
		)
		(property "Device Type" "SC70-5H44"
			(at 2.3114 -10.414 270)
			(unlocked yes)
			(layer "B.Fab")
			(hide yes)
			(effects
				(font
					(size 1.016 1.016)
					(thickness 0.1524)
				)
				(justify mirror)
			)
		)
		(duplicate_pad_numbers_are_jumpers no)
		(fp_line
			(start -1.27 1.7018)
			(end 1.27 1.7018)
			(stroke
				(width 0.1524)
				(type default)
			)
			(layer "B.SilkS")
		)
		(fp_line
			(start 1.27 1.7018)
			(end 1.27 -1.7018)
			(stroke
				(width 0.1524)
				(type default)
			)
			(layer "B.SilkS")
		)
		(fp_line
			(start -1.27 -1.7018)
			(end -1.27 1.7018)
			(stroke
				(width 0.1524)
				(type default)
			)
			(layer "B.SilkS")
		)
		(fp_line
			(start 1.27 -1.7018)
			(end -1.27 -1.7018)
			(stroke
				(width 0.1524)
				(type default)
			)
			(layer "B.SilkS")
		)
		(fp_line
			(start -1.3843 -1.8034)
			(end -1.3843 -1.1176)
			(stroke
				(width 0.3302)
				(type default)
			)
			(layer "B.SilkS")
		)
		(fp_line
			(start -0.6604 -1.8034)
			(end -1.3843 -1.8034)
			(stroke
				(width 0.3302)
				(type default)
			)
			(layer "B.SilkS")
		)
		(fp_rect
			(start 1.524 1.9558)
			(end -1.524 -1.9558)
			(stroke
				(width 0)
				(type default)
			)
			(fill no)
			(layer "B.CrtYd")
		)
		(fp_poly
			(pts
				(xy 1.524 -1.9558) (xy -1.524 -1.9558) (xy -1.524 1.9558) (xy 1.524 1.9558)
			)
			(stroke
				(width 0)
				(type default)
			)
			(fill no)
			(layer "B.Fab")
		)
		(pad "1" smd rect
			(at -0.65024 -0.8255 90)
			(size 0.4064 1.2192)
			(layers "B.Cu" "B.Mask" "B.Paste")
			(net "DEBUG_CARD_PRSNT")
		)
		(pad "2" smd rect
			(at 0 -0.8255 90)
			(size 0.4064 1.2192)
			(layers "B.Cu" "B.Mask" "B.Paste")
			(net "DEBUG_UART_IOM_TX")
		)
		(pad "3" smd rect
			(at 0.65024 -0.8255 90)
			(size 0.4064 1.2192)
			(layers "B.Cu" "B.Mask" "B.Paste")
			(net "GND")
		)
		(pad "4" smd rect
			(at 0.65024 0.8255 90)
			(size 0.4064 1.2192)
			(layers "B.Cu" "B.Mask" "B.Paste")
			(net "UART_IOM_TX")
		)
		(pad "5" smd rect
			(at -0.65024 0.8255 90)
			(size 0.4064 1.2192)
			(layers "B.Cu" "B.Mask" "B.Paste")
			(net "P3V3_STBY")
		)
	)
	(footprint ""
		(layer "B.Cu")
		(at 83.67649 -56.358536)
		(property "Reference" "C512"
			(at 0 0 0)
			(layer "B.SilkS")
			(hide yes)
			(effects
				(font
					(size 1.27 1.27)
				)
				(justify mirror)
			)
		)
		(property "Value" "SC10U16V5KX-7-GP-U"
			(at 0.076454 -6.1214 0)
			(unlocked yes)
			(layer "B.Fab")
			(hide yes)
			(effects
				(font
					(size 1.016 1.016)
					(thickness 0.1524)
				)
				(justify mirror)
			)
		)
		(property "Device Type" "C805H58"
			(at 0.0762 -8.1534 0)
			(unlocked yes)
			(layer "B.Fab")
			(hide yes)
			(effects
				(font
					(size 1.016 1.016)
					(thickness 0.1524)
				)
				(justify mirror)
			)
		)
		(duplicate_pad_numbers_are_jumpers no)
		(fp_line
			(start -0.635 0)
			(end 0.635 0)
			(stroke
				(width 0.508)
				(type default)
			)
			(layer "B.SilkS")
		)
		(fp_rect
			(start 0.9652 1.778)
			(end -0.9652 -1.778)
			(stroke
				(width 0)
				(type default)
			)
			(fill no)
			(layer "B.CrtYd")
		)
		(fp_poly
			(pts
				(xy 0.9652 -1.778) (xy -0.9652 -1.778) (xy -0.9652 1.778) (xy 0.9652 1.778)
			)
			(stroke
				(width 0)
				(type default)
			)
			(fill no)
			(layer "B.Fab")
		)
		(pad "1" smd rect
			(at 0 -0.9652 180)
			(size 1.397 1.143)
			(layers "B.Cu" "B.Mask" "B.Paste")
			(net "P3V3_STBY")
		)
		(pad "2" smd rect
			(at 0 0.9652 180)
			(size 1.397 1.143)
			(layers "B.Cu" "B.Mask" "B.Paste")
			(net "GND")
		)
	)
	(footprint ""
		(layer "B.Cu")
		(at 80.965802 -57.02046 180)
		(property "Reference" "C187"
			(at 0 0 0)
			(layer "B.SilkS")
			(hide yes)
			(effects
				(font
					(size 1.27 1.27)
				)
				(justify mirror)
			)
		)
		(property "Value" "SC10U6D3V5KX-4GP"
			(at 0.0762 -6.1214 180)
			(unlocked yes)
			(layer "B.Fab")
			(hide yes)
			(effects
				(font
					(size 1.016 1.016)
					(thickness 0.1524)
				)
				(justify mirror)
			)
		)
		(property "Device Type" "C805H58"
			(at 0.0762 -8.1534 180)
			(unlocked yes)
			(layer "B.Fab")
			(hide yes)
			(effects
				(font
					(size 1.016 1.016)
					(thickness 0.1524)
				)
				(justify mirror)
			)
		)
		(duplicate_pad_numbers_are_jumpers no)
		(fp_line
			(start -0.635 0)
			(end 0.635 0)
			(stroke
				(width 0.508)
				(type default)
			)
			(layer "B.SilkS")
		)
		(fp_rect
			(start 0.9652 1.778)
			(end -0.9652 -1.778)
			(stroke
				(width 0)
				(type default)
			)
			(fill no)
			(layer "B.CrtYd")
		)
		(fp_poly
			(pts
				(xy 0.9652 -1.778) (xy -0.9652 -1.778) (xy -0.9652 1.778) (xy 0.9652 1.778)
			)
			(stroke
				(width 0)
				(type default)
			)
			(fill no)
			(layer "B.Fab")
		)
		(pad "1" smd rect
			(at 0 -0.9652)
			(size 1.397 1.143)
			(layers "B.Cu" "B.Mask" "B.Paste")
			(net "P3V3")
		)
		(pad "2" smd rect
			(at 0 0.9652)
			(size 1.397 1.143)
			(layers "B.Cu" "B.Mask" "B.Paste")
			(net "GND")
		)
	)
)
